# T6G (Grand Teton) — schematic netlist excerpt (pin names and nets, part order shuffled) for the footprints in the layout excerpt that follows; sources: Cadence DE-HDL packaged netlist, KiCad conversion of 04192023_DAF0TMB3IC0_F0TG_MB_C_brd_V02_OCP.brd

PC6568  Q_CAPP  470UF 2.5V 20% SPCAP  pkg SMLF  page 363 : A = P0V9_CPU0_RT_2D ; B = GND
C999  Q_CAP  1UF 4V 20% X6S  pkg 0201  page 312 : A = P1V8_CPU0_RT3_1A_1D ; B = GND
C6045  Q_CAP  0.01UF 50V 10% X7R  pkg C0402  page 177 : A = P3V3_AUX_CPU0_USB_AVDD33 ; B = GND

(kicad_pcb
	(version 20260206)
	(generator "pcbnew")
	(generator_version "10.0")
	(general
		(thickness 1.6)
		(legacy_teardrops no)
	)
	(paper "A4")
	(title_block
		(title "04192023_DAF0TMB3IC0_F0TG_MB_C_brd_V02_OCP.brd")
		(comment 1 "Grand Teton / footprints 6072-6074 of 8354")
	)
	(layers
		(0 "F.Cu" signal "TOP")
		(4 "In1.Cu" signal "GND")
		(6 "In2.Cu" signal "IN1")
		(8 "In3.Cu" signal "GND1")
		(10 "In4.Cu" signal "IN2")
		(12 "In5.Cu" signal "GND2")
		(14 "In6.Cu" signal "IN3")
		(16 "In7.Cu" signal "GND3")
		(18 "In8.Cu" signal "VCC")
		(20 "In9.Cu" signal "VCC1")
		(22 "In10.Cu" signal "GND4")
		(24 "In11.Cu" signal "IN4")
		(26 "In12.Cu" signal "GND5")
		(28 "In13.Cu" signal "IN5")
		(30 "In14.Cu" signal "GND6")
		(32 "In15.Cu" signal "IN6")
		(34 "In16.Cu" signal "GND7")
		(2 "B.Cu" signal "BOTTOM")
		(9 "F.Adhes" user "F.Adhesive")
		(11 "B.Adhes" user "B.Adhesive")
		(13 "F.Paste" user "Package Geometry/Pastemask Top")
		(15 "B.Paste" user "Package Geometry/Pastemask Bottom")
		(5 "F.SilkS" user "Ref Des/Silkscreen Top")
		(7 "B.SilkS" user "Ref Des/Silkscreen Bottom")
		(1 "F.Mask" user "Board Geometry/Soldermask Top")
		(3 "B.Mask" user "Board Geometry/Soldermask Bottom")
		(17 "Dwgs.User" user "User.Drawings")
		(19 "Cmts.User" user "User.Comments")
		(21 "Eco1.User" user "User.Eco1")
		(23 "Eco2.User" user "User.Eco2")
		(25 "Edge.Cuts" user "Board Geometry/Outline")
		(27 "Margin" user)
		(31 "F.CrtYd" user "Package Geometry/Place Bound Top")
		(29 "B.CrtYd" user "Package Geometry/Place Bound Bottom")
		(35 "F.Fab" user "Ref Des/Assembly Top")
		(33 "B.Fab" user "Ref Des/Assembly Bottom")
	)
	(footprint ""
		(layer "B.Cu")
		(at 381.278384 -395.148562 90)
		(property "Reference" "C999"
			(at 0 0 90)
			(layer "B.SilkS")
			(hide yes)
			(effects
				(font
					(size 1.27 1.27)
				)
				(justify mirror)
			)
		)
		(property "Value" ""
			(at 0 0 90)
			(layer "B.Fab")
			(effects
				(font
					(size 1.27 1.27)
				)
				(justify mirror)
			)
		)
		(duplicate_pad_numbers_are_jumpers no)
		(fp_line
			(start 0.299974 -0.150114)
			(end -0.299974 -0.150114)
			(stroke
				(width 0.1)
				(type default)
			)
			(layer "B.Fab")
		)
		(fp_line
			(start -0.299974 -0.150114)
			(end -0.299974 0.150114)
			(stroke
				(width 0.1)
				(type default)
			)
			(layer "B.Fab")
		)
		(fp_line
			(start 0.299974 0.150114)
			(end 0.299974 -0.150114)
			(stroke
				(width 0.1)
				(type default)
			)
			(layer "B.Fab")
		)
		(fp_line
			(start -0.299974 0.150114)
			(end 0.299974 0.150114)
			(stroke
				(width 0.1)
				(type default)
			)
			(layer "B.Fab")
		)
		(pad "1" smd rect
			(at 0.2667 0 270)
			(size 0.3048 0.381)
			(layers "B.Cu" "B.Mask" "B.Paste")
			(net "P1V8_CPU0_RT3_1A_1D")
		)
		(pad "2" smd rect
			(at -0.2667 0 270)
			(size 0.3048 0.381)
			(layers "B.Cu" "B.Mask" "B.Paste")
			(net "GND")
		)
	)
	(footprint ""
		(layer "B.Cu")
		(at 139.36472 -35.304222 -90)
		(property "Reference" "C6045"
			(at 0 0 90)
			(layer "B.SilkS")
			(hide yes)
			(effects
				(font
					(size 1.27 1.27)
				)
				(justify mirror)
			)
		)
		(property "Value" ""
			(at 0 0 90)
			(layer "B.Fab")
			(effects
				(font
					(size 1.27 1.27)
				)
				(justify mirror)
			)
		)
		(duplicate_pad_numbers_are_jumpers no)
		(fp_line
			(start -0.7874 0.4064)
			(end 0.7874 0.4064)
			(stroke
				(width 0.1524)
				(type default)
			)
			(layer "B.SilkS")
		)
		(fp_line
			(start 0.7874 0.4064)
			(end 0.7874 -0.4064)
			(stroke
				(width 0.1524)
				(type default)
			)
			(layer "B.SilkS")
		)
		(fp_line
			(start -0.7874 -0.4064)
			(end -0.7874 0.4064)
			(stroke
				(width 0.1524)
				(type default)
			)
			(layer "B.SilkS")
		)
		(fp_line
			(start 0.7874 -0.4064)
			(end -0.7874 -0.4064)
			(stroke
				(width 0.1524)
				(type default)
			)
			(layer "B.SilkS")
		)
		(fp_line
			(start -0.67945 0.3048)
			(end -0.120396 0.3048)
			(stroke
				(width 0.1)
				(type default)
			)
			(layer "B.Fab")
		)
		(fp_line
			(start -0.120396 0.3048)
			(end -0.120396 0.2794)
			(stroke
				(width 0.1)
				(type default)
			)
			(layer "B.Fab")
		)
		(fp_line
			(start 0.12065 0.3048)
			(end 0.67945 0.3048)
			(stroke
				(width 0.1)
				(type default)
			)
			(layer "B.Fab")
		)
		(fp_line
			(start 0.67945 0.3048)
			(end 0.67945 -0.305054)
			(stroke
				(width 0.1)
				(type default)
			)
			(layer "B.Fab")
		)
		(fp_line
			(start -0.120396 0.2794)
			(end 0.12065 0.2794)
			(stroke
				(width 0.1)
				(type default)
			)
			(layer "B.Fab")
		)
		(fp_line
			(start 0.12065 0.2794)
			(end 0.12065 0.3048)
			(stroke
				(width 0.1)
				(type default)
			)
			(layer "B.Fab")
		)
		(fp_line
			(start -0.12065 -0.2794)
			(end -0.12065 -0.3048)
			(stroke
				(width 0.1)
				(type default)
			)
			(layer "B.Fab")
		)
		(fp_line
			(start 0.12065 -0.2794)
			(end -0.12065 -0.2794)
			(stroke
				(width 0.1)
				(type default)
			)
			(layer "B.Fab")
		)
		(fp_line
			(start -0.67945 -0.3048)
			(end -0.67945 0.3048)
			(stroke
				(width 0.1)
				(type default)
			)
			(layer "B.Fab")
		)
		(fp_line
			(start -0.12065 -0.3048)
			(end -0.67945 -0.3048)
			(stroke
				(width 0.1)
				(type default)
			)
			(layer "B.Fab")
		)
		(fp_line
			(start 0.12065 -0.305054)
			(end 0.12065 -0.2794)
			(stroke
				(width 0.1)
				(type default)
			)
			(layer "B.Fab")
		)
		(fp_line
			(start 0.67945 -0.305054)
			(end 0.12065 -0.305054)
			(stroke
				(width 0.1)
				(type default)
			)
			(layer "B.Fab")
		)
		(pad "1" smd circle
			(at 0.40005 0 90)
			(size 0 0)
			(layers "B.Cu" "B.Mask" "B.Paste")
			(net "P3V3_AUX_CPU0_USB_AVDD33")
		)
		(pad "2" smd circle
			(at -0.40005 0 90)
			(size 0 0)
			(layers "B.Cu" "B.Mask" "B.Paste")
			(net "GND")
		)
	)
	(footprint ""
		(layer "B.Cu")
		(at 444.166752 -380.027434 90)
		(property "Reference" "PC6568"
			(at -6.293104 2.238248 0)
			(unlocked yes)
			(layer "B.SilkS")
			(effects
				(font
					(size 0.7874 0.5842)
					(thickness 0.1524)
				)
				(justify left mirror)
			)
		)
		(property "Value" ""
			(at 0 0 90)
			(layer "B.Fab")
			(effects
				(font
					(size 1.27 1.27)
				)
				(justify mirror)
			)
		)
		(duplicate_pad_numbers_are_jumpers no)
		(fp_line
			(start 4.84378 -2.150618)
			(end 4.53898 -2.150618)
			(stroke
				(width 0.1524)
				(type default)
			)
			(layer "B.SilkS")
		)
		(fp_line
			(start 4.84378 -2.150618)
			(end 4.842256 2.163064)
			(stroke
				(width 0.1524)
				(type default)
			)
			(layer "B.SilkS")
		)
		(fp_line
			(start 4.69138 -2.150618)
			(end 4.692396 2.161032)
			(stroke
				(width 0.1524)
				(type default)
			)
			(layer "B.SilkS")
		)
		(fp_line
			(start 4.53898 -2.150618)
			(end 4.539742 2.152142)
			(stroke
				(width 0.1524)
				(type default)
			)
			(layer "B.SilkS")
		)
		(fp_line
			(start 4.53898 -2.15011)
			(end -4.53898 -2.15011)
			(stroke
				(width 0.1524)
				(type default)
			)
			(layer "B.SilkS")
		)
		(fp_line
			(start -4.53898 -2.15011)
			(end -4.53898 2.15011)
			(stroke
				(width 0.1524)
				(type default)
			)
			(layer "B.SilkS")
		)
		(fp_line
			(start 4.53898 2.15011)
			(end 4.53898 -2.15011)
			(stroke
				(width 0.1524)
				(type default)
			)
			(layer "B.SilkS")
		)
		(fp_line
			(start -4.53898 2.15011)
			(end 4.53898 2.15011)
			(stroke
				(width 0.1524)
				(type default)
			)
			(layer "B.SilkS")
		)
		(fp_line
			(start 4.83108 2.150364)
			(end 4.447794 2.149348)
			(stroke
				(width 0.1524)
				(type default)
			)
			(layer "B.SilkS")
		)
		(fp_line
			(start 3.64998 -2.15011)
			(end -3.64998 -2.15011)
			(stroke
				(width 0.1)
				(type default)
			)
			(layer "B.Fab")
		)
		(fp_line
			(start -3.64998 -2.15011)
			(end -3.64998 2.15011)
			(stroke
				(width 0.1)
				(type default)
			)
			(layer "B.Fab")
		)
		(fp_line
			(start 3.64998 2.15011)
			(end 3.64998 -2.15011)
			(stroke
				(width 0.1)
				(type default)
			)
			(layer "B.Fab")
		)
		(fp_line
			(start -3.64998 2.15011)
			(end 3.64998 2.15011)
			(stroke
				(width 0.1)
				(type default)
			)
			(layer "B.Fab")
		)
		(fp_text user "+"
			(at 5.993638 -2.411222 90)
			(unlocked yes)
			(layer "B.SilkS")
			(effects
				(font
					(size 1.905 1.4224)
					(thickness 0.1524)
				)
				(justify left mirror)
			)
		)
		(fp_text user "-"
			(at -4.313174 -0.094488 90)
			(unlocked yes)
			(layer "B.SilkS")
			(effects
				(font
					(size 1.905 1.4224)
					(thickness 0.1524)
				)
				(justify left mirror)
			)
		)
		(fp_text user "+"
			(at 6.214872 -0.337058 90)
			(unlocked yes)
			(layer "B.Fab")
			(effects
				(font
					(size 1.905 1.4224)
					(thickness 0.1524)
				)
				(justify left mirror)
			)
		)
		(fp_text user "-"
			(at -4.313174 -0.094488 90)
			(unlocked yes)
			(layer "B.Fab")
			(effects
				(font
					(size 1.905 1.4224)
					(thickness 0.1524)
				)
				(justify left mirror)
			)
		)
		(pad "1" smd rect
			(at 3.199892 0 270)
			(size 2.413 2.8194)
			(layers "B.Cu" "B.Mask" "B.Paste")
			(net "P0V9_CPU0_RT_2D")
		)
		(pad "2" smd rect
			(at -3.199892 0 270)
			(size 2.413 2.8194)
			(layers "B.Cu" "B.Mask" "B.Paste")
			(net "GND")
		)
	)
)
